FILE_TYPE = CONNECTIVITY;
{Allegro Design Entry HDL 17.2-2016 S081 (4005846) 1/11/2022}
"PAGE_NUMBER" = 134;
0"NC";
END.
